# S9S_MB_2U (Grand Teton) — schematic netlist excerpt (pin names and nets, part order shuffled) for the footprints in the layout excerpt that follows; sources: Cadence DE-HDL packaged netlist, KiCad conversion of 03242023_DA0F0TMBIJ0_F0T_Motherboard_J_brd_V01_OCP.brd

R3955  Q_RES  0 5% EMPTY  pkg 0402LF  page 193 : A = P12V_E1S_IMON_0 ; B = P12V_E1S_0_ISENSE_MPS_MAM
R4718  Q_RES  33.2 1% EMPTY  pkg 0402LF  page 224 : A = FM_AC_PWR_BTN_PLD_ISO_R_N ; B = FM_AC_PWR_BTN_PLD_ISO_N

(kicad_pcb
	(version 20260206)
	(generator "pcbnew")
	(generator_version "10.0")
	(general
		(thickness 1.6)
		(legacy_teardrops no)
	)
	(paper "A4")
	(title_block
		(title "03242023_DA0F0TMBIJ0_F0T_Motherboard_J_brd_V01_OCP.brd")
		(comment 1 "Grand Teton / footprints 2728-2729 of 6105")
	)
	(layers
		(0 "F.Cu" signal "TOP")
		(4 "In1.Cu" signal "GND")
		(6 "In2.Cu" signal "IN1")
		(8 "In3.Cu" signal "GND1")
		(10 "In4.Cu" signal "IN2")
		(12 "In5.Cu" signal "GND2")
		(14 "In6.Cu" signal "IN3")
		(16 "In7.Cu" signal "GND3")
		(18 "In8.Cu" signal "VCC")
		(20 "In9.Cu" signal "VCC1")
		(22 "In10.Cu" signal "GND4")
		(24 "In11.Cu" signal "IN4")
		(26 "In12.Cu" signal "GND5")
		(28 "In13.Cu" signal "IN5")
		(30 "In14.Cu" signal "GND6")
		(32 "In15.Cu" signal "IN6")
		(34 "In16.Cu" signal "GND7")
		(2 "B.Cu" signal "BOTTOM")
		(9 "F.Adhes" user "F.Adhesive")
		(11 "B.Adhes" user "B.Adhesive")
		(13 "F.Paste" user "Package Geometry/Pastemask Top")
		(15 "B.Paste" user "Package Geometry/Pastemask Bottom")
		(5 "F.SilkS" user "Ref Des/Silkscreen Top")
		(7 "B.SilkS" user "Ref Des/Silkscreen Bottom")
		(1 "F.Mask" user "Board Geometry/Soldermask Top")
		(3 "B.Mask" user "Board Geometry/Soldermask Bottom")
		(17 "Dwgs.User" user "User.Drawings")
		(19 "Cmts.User" user "User.Comments")
		(21 "Eco1.User" user "User.Eco1")
		(23 "Eco2.User" user "User.Eco2")
		(25 "Edge.Cuts" user "Board Geometry/Outline")
		(27 "Margin" user)
		(31 "F.CrtYd" user "Package Geometry/Place Bound Top")
		(29 "B.CrtYd" user "Package Geometry/Place Bound Bottom")
		(35 "F.Fab" user "Ref Des/Assembly Top")
		(33 "B.Fab" user "Ref Des/Assembly Bottom")
	)
	(footprint ""
		(layer "F.Cu")
		(at 208.49336 -120.1166 180)
		(property "Reference" "R4718"
			(at 0 0 180)
			(layer "F.SilkS")
			(hide yes)
			(effects
				(font
					(size 1.27 1.27)
				)
			)
		)
		(property "Value" ""
			(at 0 0 180)
			(layer "F.Fab")
			(effects
				(font
					(size 1.27 1.27)
				)
			)
		)
		(duplicate_pad_numbers_are_jumpers no)
		(fp_line
			(start 0.7874 0.4064)
			(end -0.7874 0.4064)
			(stroke
				(width 0.1524)
				(type default)
			)
			(layer "F.SilkS")
		)
		(fp_line
			(start 0.7874 -0.4064)
			(end 0.7874 0.4064)
			(stroke
				(width 0.1524)
				(type default)
			)
			(layer "F.SilkS")
		)
		(fp_line
			(start -0.7874 0.4064)
			(end -0.7874 -0.4064)
			(stroke
				(width 0.1524)
				(type default)
			)
			(layer "F.SilkS")
		)
		(fp_line
			(start -0.7874 -0.4064)
			(end 0.7874 -0.4064)
			(stroke
				(width 0.1524)
				(type default)
			)
			(layer "F.SilkS")
		)
		(fp_line
			(start 0.67945 0.3048)
			(end 0.120396 0.3048)
			(stroke
				(width 0.1)
				(type default)
			)
			(layer "F.Fab")
		)
		(fp_line
			(start 0.67945 -0.3048)
			(end 0.67945 0.3048)
			(stroke
				(width 0.1)
				(type default)
			)
			(layer "F.Fab")
		)
		(fp_line
			(start 0.12065 -0.2794)
			(end 0.12065 -0.3048)
			(stroke
				(width 0.1)
				(type default)
			)
			(layer "F.Fab")
		)
		(fp_line
			(start 0.12065 -0.3048)
			(end 0.67945 -0.3048)
			(stroke
				(width 0.1)
				(type default)
			)
			(layer "F.Fab")
		)
		(fp_line
			(start 0.120396 0.3048)
			(end 0.120396 0.2794)
			(stroke
				(width 0.1)
				(type default)
			)
			(layer "F.Fab")
		)
		(fp_line
			(start 0.120396 0.2794)
			(end -0.12065 0.2794)
			(stroke
				(width 0.1)
				(type default)
			)
			(layer "F.Fab")
		)
		(fp_line
			(start -0.12065 0.3048)
			(end -0.67945 0.3048)
			(stroke
				(width 0.1)
				(type default)
			)
			(layer "F.Fab")
		)
		(fp_line
			(start -0.12065 0.2794)
			(end -0.12065 0.3048)
			(stroke
				(width 0.1)
				(type default)
			)
			(layer "F.Fab")
		)
		(fp_line
			(start -0.12065 -0.2794)
			(end 0.12065 -0.2794)
			(stroke
				(width 0.1)
				(type default)
			)
			(layer "F.Fab")
		)
		(fp_line
			(start -0.12065 -0.305054)
			(end -0.12065 -0.2794)
			(stroke
				(width 0.1)
				(type default)
			)
			(layer "F.Fab")
		)
		(fp_line
			(start -0.67945 0.3048)
			(end -0.67945 -0.305054)
			(stroke
				(width 0.1)
				(type default)
			)
			(layer "F.Fab")
		)
		(fp_line
			(start -0.67945 -0.305054)
			(end -0.12065 -0.305054)
			(stroke
				(width 0.1)
				(type default)
			)
			(layer "F.Fab")
		)
		(pad "1" smd circle
			(at -0.40005 0 180)
			(size 0 0)
			(layers "F.Cu" "F.Mask" "F.Paste")
			(net "FM_AC_PWR_BTN_PLD_ISO_R_N")
		)
		(pad "2" smd circle
			(at 0.40005 0 180)
			(size 0 0)
			(layers "F.Cu" "F.Mask" "F.Paste")
			(net "FM_AC_PWR_BTN_PLD_ISO_N")
		)
	)
	(footprint ""
		(layer "F.Cu")
		(at 257.85953 -56.495442)
		(property "Reference" "R3955"
			(at 0 0 0)
			(layer "F.SilkS")
			(hide yes)
			(effects
				(font
					(size 1.27 1.27)
				)
			)
		)
		(property "Value" ""
			(at 0 0 0)
			(layer "F.Fab")
			(effects
				(font
					(size 1.27 1.27)
				)
			)
		)
		(duplicate_pad_numbers_are_jumpers no)
		(fp_line
			(start -0.7874 -0.4064)
			(end 0.7874 -0.4064)
			(stroke
				(width 0.1524)
				(type default)
			)
			(layer "F.SilkS")
		)
		(fp_line
			(start -0.7874 0.4064)
			(end -0.7874 -0.4064)
			(stroke
				(width 0.1524)
				(type default)
			)
			(layer "F.SilkS")
		)
		(fp_line
			(start 0.7874 -0.4064)
			(end 0.7874 0.4064)
			(stroke
				(width 0.1524)
				(type default)
			)
			(layer "F.SilkS")
		)
		(fp_line
			(start 0.7874 0.4064)
			(end -0.7874 0.4064)
			(stroke
				(width 0.1524)
				(type default)
			)
			(layer "F.SilkS")
		)
		(fp_line
			(start -0.67945 -0.305054)
			(end -0.12065 -0.305054)
			(stroke
				(width 0.1)
				(type default)
			)
			(layer "F.Fab")
		)
		(fp_line
			(start -0.67945 0.3048)
			(end -0.67945 -0.305054)
			(stroke
				(width 0.1)
				(type default)
			)
			(layer "F.Fab")
		)
		(fp_line
			(start -0.12065 -0.305054)
			(end -0.12065 -0.2794)
			(stroke
				(width 0.1)
				(type default)
			)
			(layer "F.Fab")
		)
		(fp_line
			(start -0.12065 -0.2794)
			(end 0.12065 -0.2794)
			(stroke
				(width 0.1)
				(type default)
			)
			(layer "F.Fab")
		)
		(fp_line
			(start -0.12065 0.2794)
			(end -0.12065 0.3048)
			(stroke
				(width 0.1)
				(type default)
			)
			(layer "F.Fab")
		)
		(fp_line
			(start -0.12065 0.3048)
			(end -0.67945 0.3048)
			(stroke
				(width 0.1)
				(type default)
			)
			(layer "F.Fab")
		)
		(fp_line
			(start 0.120396 0.2794)
			(end -0.12065 0.2794)
			(stroke
				(width 0.1)
				(type default)
			)
			(layer "F.Fab")
		)
		(fp_line
			(start 0.120396 0.3048)
			(end 0.120396 0.2794)
			(stroke
				(width 0.1)
				(type default)
			)
			(layer "F.Fab")
		)
		(fp_line
			(start 0.12065 -0.3048)
			(end 0.67945 -0.3048)
			(stroke
				(width 0.1)
				(type default)
			)
			(layer "F.Fab")
		)
		(fp_line
			(start 0.12065 -0.2794)
			(end 0.12065 -0.3048)
			(stroke
				(width 0.1)
				(type default)
			)
			(layer "F.Fab")
		)
		(fp_line
			(start 0.67945 -0.3048)
			(end 0.67945 0.3048)
			(stroke
				(width 0.1)
				(type default)
			)
			(layer "F.Fab")
		)
		(fp_line
			(start 0.67945 0.3048)
			(end 0.120396 0.3048)
			(stroke
				(width 0.1)
				(type default)
			)
			(layer "F.Fab")
		)
		(pad "1" smd circle
			(at -0.40005 0)
			(size 0 0)
			(layers "F.Cu" "F.Mask" "F.Paste")
			(net "P12V_E1S_IMON_0")
		)
		(pad "2" smd circle
			(at 0.40005 0)
			(size 0 0)
			(layers "F.Cu" "F.Mask" "F.Paste")
			(net "P12V_E1S_0_ISENSE_MPS_MAM")
		)
	)
)
